(kicad_pcb
	(version 20260206)
	(generator "pcbnew")
	(generator_version "10.0")
	(general
		(thickness 1.6)
		(legacy_teardrops no)
	)
	(paper "A4")
	(title_block
		(title "Bryce Canyon_IOM_IOC_16318-2_OCP.brd")
		(comment 1 "Bryce Canyon / footprints 825-829 of 1605")
	)
	(layers
		(0 "F.Cu" signal "TOP")
		(4 "In1.Cu" signal "L2GND")
		(6 "In2.Cu" signal "L3")
		(8 "In3.Cu" signal "L4VCC")
		(10 "In4.Cu" signal "L5VCC")
		(12 "In5.Cu" signal "L6")
		(14 "In6.Cu" signal "L7GND")
		(2 "B.Cu" signal "BOTTOM")
		(9 "F.Adhes" user "F.Adhesive")
		(11 "B.Adhes" user "B.Adhesive")
		(13 "F.Paste" user "Package Geometry/Pastemask Top")
		(15 "B.Paste" user "Package Geometry/Pastemask Bottom")
		(5 "F.SilkS" user "Ref Des/Silkscreen Top")
		(7 "B.SilkS" user "Ref Des/Silkscreen Bottom")
		(1 "F.Mask" user "Board Geometry/Soldermask Top")
		(3 "B.Mask" user "Board Geometry/Soldermask Bottom")
		(17 "Dwgs.User" user "User.Drawings")
		(19 "Cmts.User" user "User.Comments")
		(21 "Eco1.User" user "User.Eco1")
		(23 "Eco2.User" user "User.Eco2")
		(25 "Edge.Cuts" user "Board Geometry/Outline")
		(27 "Margin" user)
		(31 "F.CrtYd" user "Package Geometry/Place Bound Top")
		(29 "B.CrtYd" user "Package Geometry/Place Bound Bottom")
		(35 "F.Fab" user "Ref Des/Assembly Top")
		(33 "B.Fab" user "Ref Des/Assembly Bottom")
	)
	(footprint ""
		(layer "F.Cu")
		(at 46.011084 -161.368232 180)
		(property "Reference" "R180"
			(at 0 0 180)
			(layer "F.SilkS")
			(hide yes)
			(effects
				(font
					(size 1.27 1.27)
				)
			)
		)
		(property "Value" "2K2R2F-GP"
			(at 0.064008 -3.993896 180)
			(unlocked yes)
			(layer "F.Fab")
			(hide yes)
			(effects
				(font
					(size 1.016 1.016)
					(thickness 0.1524)
				)
			)
		)
		(property "Device Type" "R402H16"
			(at 0.064008 -5.517896 180)
			(unlocked yes)
			(layer "F.Fab")
			(hide yes)
			(effects
				(font
					(size 1.016 1.016)
					(thickness 0.1524)
				)
			)
		)
		(duplicate_pad_numbers_are_jumpers no)
		(fp_line
			(start 0.508 -0.9398)
			(end -0.508 -0.9398)
			(stroke
				(width 0.1524)
				(type default)
			)
			(layer "F.SilkS")
		)
		(fp_line
			(start -0.508 -0.9398)
			(end -0.508 0.9398)
			(stroke
				(width 0.1524)
				(type default)
			)
			(layer "F.SilkS")
		)
		(fp_rect
			(start -0.508 0.9398)
			(end 0.508 -0.9398)
			(stroke
				(width 0)
				(type default)
			)
			(fill no)
			(layer "F.CrtYd")
		)
		(fp_rect
			(start -0.508 0.9398)
			(end 0.508 -0.9398)
			(stroke
				(width 0)
				(type default)
			)
			(fill no)
			(layer "F.Fab")
		)
		(pad "1" smd custom
			(at 0 -0.4445 180)
			(size 0.1397 0.1397)
			(layers "F.Cu" "F.Mask" "F.Paste")
			(net "I2C_DPB_SDA_OUT")
			(options
				(clearance outline)
				(anchor circle)
			)
			(primitives
				(gr_poly
					(pts
						(arc
							(start -0.1778 -0.2794)
							(mid -0.249642 -0.249642)
							(end -0.2794 -0.1778)
						)
						(arc
							(start -0.2794 0.1778)
							(mid -0.249642 0.249642)
							(end -0.1778 0.2794)
						)
						(arc
							(start 0.1778 0.2794)
							(mid 0.249642 0.249642)
							(end 0.2794 0.1778)
						)
						(arc
							(start 0.2794 -0.1778)
							(mid 0.249642 -0.249642)
							(end 0.1778 -0.2794)
						)
					)
					(width 0)
					(fill yes)
				)
			)
		)
		(pad "2" smd custom
			(at 0 0.4445 180)
			(size 0.1397 0.1397)
			(layers "F.Cu" "F.Mask" "F.Paste")
			(net "P3V3_STBY")
			(options
				(clearance outline)
				(anchor circle)
			)
			(primitives
				(gr_poly
					(pts
						(arc
							(start -0.1778 -0.2794)
							(mid -0.249642 -0.249642)
							(end -0.2794 -0.1778)
						)
						(arc
							(start -0.2794 0.1778)
							(mid -0.249642 0.249642)
							(end -0.1778 0.2794)
						)
						(arc
							(start 0.1778 0.2794)
							(mid 0.249642 0.249642)
							(end 0.2794 0.1778)
						)
						(arc
							(start 0.2794 -0.1778)
							(mid 0.249642 -0.249642)
							(end 0.1778 -0.2794)
						)
					)
					(width 0)
					(fill yes)
				)
			)
		)
	)
	(footprint ""
		(layer "F.Cu")
		(at 77.283818 -93.355668 90)
		(property "Reference" "VIA8"
			(at 0 0 90)
			(layer "F.SilkS")
			(hide yes)
			(effects
				(font
					(size 1.27 1.27)
				)
			)
		)
		(property "Value" "85OHM-8L-1D6MM-L16L18-GP"
			(at 4.064 0.6096 90)
			(unlocked yes)
			(layer "F.Fab")
			(hide yes)
			(effects
				(font
					(size 1.016 1.016)
					(thickness 0.1524)
				)
			)
		)
		(property "Device Type" "VIA-PCIE-4P-368076"
			(at 4.064 -0.9144 90)
			(unlocked yes)
			(layer "F.Fab")
			(hide yes)
			(effects
				(font
					(size 1.016 1.016)
					(thickness 0.1524)
				)
			)
		)
		(duplicate_pad_numbers_are_jumpers no)
		(fp_rect
			(start -1.8415 0.381)
			(end 1.8415 -0.381)
			(stroke
				(width 0)
				(type default)
			)
			(fill no)
			(layer "F.CrtYd")
		)
		(fp_rect
			(start -1.8415 0.381)
			(end 1.8415 -0.381)
			(stroke
				(width 0)
				(type default)
			)
			(fill no)
			(layer "F.Fab")
		)
		(pad "1" thru_hole circle
			(at -1.4605 0 90)
			(size 0.508 0.508)
			(drill 0.254)
			(layers "*.Cu" "*.Mask")
			(remove_unused_layers no)
			(net "GND")
			(clearance 0.127)
			(thermal_gap 0.127)
		)
		(pad "2" thru_hole circle
			(at -0.4445 0 90)
			(size 0.508 0.508)
			(drill 0.254)
			(layers "*.Cu" "*.Mask")
			(remove_unused_layers no)
			(net "PCIE_COMP_TO_IOM_23_DP")
			(clearance 0.127)
			(thermal_gap 0.127)
		)
		(pad "3" thru_hole circle
			(at 0.4445 0 90)
			(size 0.508 0.508)
			(drill 0.254)
			(layers "*.Cu" "*.Mask")
			(remove_unused_layers no)
			(net "PCIE_COMP_TO_IOM_23_DN")
			(clearance 0.127)
			(thermal_gap 0.127)
		)
		(pad "4" thru_hole circle
			(at 1.4605 0 90)
			(size 0.508 0.508)
			(drill 0.254)
			(layers "*.Cu" "*.Mask")
			(remove_unused_layers no)
			(net "GND")
			(clearance 0.127)
			(thermal_gap 0.127)
		)
	)
	(footprint ""
		(layer "F.Cu")
		(at 197.379336 -133.2865 180)
		(property "Reference" "R552"
			(at 0 0 180)
			(layer "F.SilkS")
			(hide yes)
			(effects
				(font
					(size 1.27 1.27)
				)
			)
		)
		(property "Value" "4K7R2F-GP"
			(at 0.064008 -3.993896 180)
			(unlocked yes)
			(layer "F.Fab")
			(hide yes)
			(effects
				(font
					(size 1.016 1.016)
					(thickness 0.1524)
				)
			)
		)
		(property "Device Type" "R402H16"
			(at 0.064008 -5.517896 180)
			(unlocked yes)
			(layer "F.Fab")
			(hide yes)
			(effects
				(font
					(size 1.016 1.016)
					(thickness 0.1524)
				)
			)
		)
		(duplicate_pad_numbers_are_jumpers no)
		(fp_line
			(start 0.508 -0.9398)
			(end -0.508 -0.9398)
			(stroke
				(width 0.1524)
				(type default)
			)
			(layer "F.SilkS")
		)
		(fp_line
			(start -0.508 -0.9398)
			(end -0.508 0.9398)
			(stroke
				(width 0.1524)
				(type default)
			)
			(layer "F.SilkS")
		)
		(fp_rect
			(start -0.508 0.9398)
			(end 0.508 -0.9398)
			(stroke
				(width 0)
				(type default)
			)
			(fill no)
			(layer "F.CrtYd")
		)
		(fp_rect
			(start -0.508 0.9398)
			(end 0.508 -0.9398)
			(stroke
				(width 0)
				(type default)
			)
			(fill no)
			(layer "F.Fab")
		)
		(pad "1" smd custom
			(at 0 -0.4445 180)
			(size 0.1397 0.1397)
			(layers "F.Cu" "F.Mask" "F.Paste")
			(net "P1V8")
			(options
				(clearance outline)
				(anchor circle)
			)
			(primitives
				(gr_poly
					(pts
						(arc
							(start -0.1778 -0.2794)
							(mid -0.249642 -0.249642)
							(end -0.2794 -0.1778)
						)
						(arc
							(start -0.2794 0.1778)
							(mid -0.249642 0.249642)
							(end -0.1778 0.2794)
						)
						(arc
							(start 0.1778 0.2794)
							(mid 0.249642 0.249642)
							(end 0.2794 0.1778)
						)
						(arc
							(start 0.2794 -0.1778)
							(mid 0.249642 -0.249642)
							(end 0.1778 -0.2794)
						)
					)
					(width 0)
					(fill yes)
				)
			)
		)
		(pad "2" smd custom
			(at 0 0.4445 180)
			(size 0.1397 0.1397)
			(layers "F.Cu" "F.Mask" "F.Paste")
			(net "Q9_G")
			(options
				(clearance outline)
				(anchor circle)
			)
			(primitives
				(gr_poly
					(pts
						(arc
							(start -0.1778 -0.2794)
							(mid -0.249642 -0.249642)
							(end -0.2794 -0.1778)
						)
						(arc
							(start -0.2794 0.1778)
							(mid -0.249642 0.249642)
							(end -0.1778 0.2794)
						)
						(arc
							(start 0.1778 0.2794)
							(mid 0.249642 0.249642)
							(end 0.2794 0.1778)
						)
						(arc
							(start 0.2794 -0.1778)
							(mid 0.249642 -0.249642)
							(end 0.1778 -0.2794)
						)
					)
					(width 0)
					(fill yes)
				)
			)
		)
	)
	(footprint ""
		(layer "F.Cu")
		(at 75.1332 -144.7038 90)
		(property "Reference" "R132"
			(at 0 0 90)
			(layer "F.SilkS")
			(hide yes)
			(effects
				(font
					(size 1.27 1.27)
				)
			)
		)
		(property "Value" "0R2J-2-GP"
			(at 0.064008 -3.993896 90)
			(unlocked yes)
			(layer "F.Fab")
			(hide yes)
			(effects
				(font
					(size 1.016 1.016)
					(thickness 0.1524)
				)
			)
		)
		(property "Device Type" "R402H16"
			(at 0.064008 -5.517896 90)
			(unlocked yes)
			(layer "F.Fab")
			(hide yes)
			(effects
				(font
					(size 1.016 1.016)
					(thickness 0.1524)
				)
			)
		)
		(duplicate_pad_numbers_are_jumpers no)
		(fp_line
			(start 0.508 -0.9398)
			(end -0.508 -0.9398)
			(stroke
				(width 0.1524)
				(type default)
			)
			(layer "F.SilkS")
		)
		(fp_line
			(start -0.508 -0.9398)
			(end -0.508 0.9398)
			(stroke
				(width 0.1524)
				(type default)
			)
			(layer "F.SilkS")
		)
		(fp_rect
			(start -0.508 0.9398)
			(end 0.508 -0.9398)
			(stroke
				(width 0)
				(type default)
			)
			(fill no)
			(layer "F.CrtYd")
		)
		(fp_rect
			(start -0.508 0.9398)
			(end 0.508 -0.9398)
			(stroke
				(width 0)
				(type default)
			)
			(fill no)
			(layer "F.Fab")
		)
		(pad "1" smd custom
			(at 0 -0.4445 90)
			(size 0.1397 0.1397)
			(layers "F.Cu" "F.Mask" "F.Paste")
			(net "I2C_SCC_SDA")
			(options
				(clearance outline)
				(anchor circle)
			)
			(primitives
				(gr_poly
					(pts
						(arc
							(start -0.1778 -0.2794)
							(mid -0.249642 -0.249642)
							(end -0.2794 -0.1778)
						)
						(arc
							(start -0.2794 0.1778)
							(mid -0.249642 0.249642)
							(end -0.1778 0.2794)
						)
						(arc
							(start 0.1778 0.2794)
							(mid 0.249642 0.249642)
							(end 0.2794 0.1778)
						)
						(arc
							(start 0.2794 -0.1778)
							(mid 0.249642 -0.249642)
							(end 0.1778 -0.2794)
						)
					)
					(width 0)
					(fill yes)
				)
			)
		)
		(pad "2" smd custom
			(at 0 0.4445 90)
			(size 0.1397 0.1397)
			(layers "F.Cu" "F.Mask" "F.Paste")
			(net "I2C_SCC_SDA_R")
			(options
				(clearance outline)
				(anchor circle)
			)
			(primitives
				(gr_poly
					(pts
						(arc
							(start -0.1778 -0.2794)
							(mid -0.249642 -0.249642)
							(end -0.2794 -0.1778)
						)
						(arc
							(start -0.2794 0.1778)
							(mid -0.249642 0.249642)
							(end -0.1778 0.2794)
						)
						(arc
							(start 0.1778 0.2794)
							(mid 0.249642 0.249642)
							(end 0.2794 0.1778)
						)
						(arc
							(start 0.2794 -0.1778)
							(mid 0.249642 -0.249642)
							(end 0.1778 -0.2794)
						)
					)
					(width 0)
					(fill yes)
				)
			)
		)
	)
	(footprint ""
		(layer "F.Cu")
		(at 23.999952 -8.750046)
		(property "Reference" "PWR1"
			(at 0 0 0)
			(layer "F.SilkS")
			(hide yes)
			(effects
				(font
					(size 1.27 1.27)
				)
			)
		)
		(property "Value" "SW-TACT-4P-169-GP"
			(at -5.715 -0.8509 0)
			(unlocked yes)
			(layer "F.Fab")
			(hide yes)
			(effects
				(font
					(size 1.016 1.016)
					(thickness 0.1524)
				)
			)
		)
		(property "Device Type" "DTSA-65N-K-S-V-676-K"
			(at -5.715 -2.3749 0)
			(unlocked yes)
			(layer "F.Fab")
			(hide yes)
			(effects
				(font
					(size 1.016 1.016)
					(thickness 0.1524)
				)
			)
		)
		(duplicate_pad_numbers_are_jumpers no)
		(fp_line
			(start -4.4958 -4.2418)
			(end -2.54 -4.2418)
			(stroke
				(width 0.1524)
				(type default)
			)
			(layer "F.SilkS")
		)
		(fp_line
			(start -4.4958 -1.5367)
			(end -4.4958 -4.2418)
			(stroke
				(width 0.1524)
				(type default)
			)
			(layer "F.SilkS")
		)
		(fp_line
			(start -3.9497 -1.5367)
			(end -4.4958 -1.5367)
			(stroke
				(width 0.1524)
				(type default)
			)
			(layer "F.SilkS")
		)
		(fp_line
			(start -3.9497 3.2004)
			(end -3.9497 -1.5367)
			(stroke
				(width 0.1524)
				(type default)
			)
			(layer "F.SilkS")
		)
		(fp_line
			(start -2.54 -4.2418)
			(end -2.54 -2.0574)
			(stroke
				(width 0.1524)
				(type default)
			)
			(layer "F.SilkS")
		)
		(fp_line
			(start -2.54 -2.0574)
			(end 2.54 -2.0574)
			(stroke
				(width 0.1524)
				(type default)
			)
			(layer "F.SilkS")
		)
		(fp_line
			(start -2.0066 3.2004)
			(end -3.9497 3.2004)
			(stroke
				(width 0.1524)
				(type default)
			)
			(layer "F.SilkS")
		)
		(fp_line
			(start -2.0066 8.6106)
			(end -2.0066 3.2004)
			(stroke
				(width 0.1524)
				(type default)
			)
			(layer "F.SilkS")
		)
		(fp_line
			(start 2.0066 3.2004)
			(end 2.0066 8.6106)
			(stroke
				(width 0.1524)
				(type default)
			)
			(layer "F.SilkS")
		)
		(fp_line
			(start 2.0066 8.6106)
			(end -2.0066 8.6106)
			(stroke
				(width 0.1524)
				(type default)
			)
			(layer "F.SilkS")
		)
		(fp_line
			(start 2.54 -4.2418)
			(end 4.4958 -4.2418)
			(stroke
				(width 0.1524)
				(type default)
			)
			(layer "F.SilkS")
		)
		(fp_line
			(start 2.54 -2.0574)
			(end 2.54 -4.2418)
			(stroke
				(width 0.1524)
				(type default)
			)
			(layer "F.SilkS")
		)
		(fp_line
			(start 3.9497 -1.5367)
			(end 3.9497 3.2004)
			(stroke
				(width 0.1524)
				(type default)
			)
			(layer "F.SilkS")
		)
		(fp_line
			(start 3.9497 3.2004)
			(end 2.0066 3.2004)
			(stroke
				(width 0.1524)
				(type default)
			)
			(layer "F.SilkS")
		)
		(fp_line
			(start 4.4958 -4.2418)
			(end 4.4958 -1.5367)
			(stroke
				(width 0.1524)
				(type default)
			)
			(layer "F.SilkS")
		)
		(fp_line
			(start 4.4958 -1.5367)
			(end 3.9497 -1.5367)
			(stroke
				(width 0.1524)
				(type default)
			)
			(layer "F.SilkS")
		)
		(fp_circle
			(center -3.50012 -2.500122)
			(end -2.43332 -2.500122)
			(stroke
				(width 0.3048)
				(type default)
			)
			(fill no)
			(layer "F.SilkS")
		)
		(fp_circle
			(center -2.249932 0)
			(end -1.183132 0)
			(stroke
				(width 0.3048)
				(type default)
			)
			(fill no)
			(layer "F.SilkS")
		)
		(fp_circle
			(center 2.249932 0)
			(end 3.316732 0)
			(stroke
				(width 0.3048)
				(type default)
			)
			(fill no)
			(layer "F.SilkS")
		)
		(fp_circle
			(center 3.50012 -2.500122)
			(end 4.56692 -2.500122)
			(stroke
				(width 0.3048)
				(type default)
			)
			(fill no)
			(layer "F.SilkS")
		)
		(fp_poly
			(pts
				(xy -1.7526 8.3566) (xy -1.7526 2.9464) (xy -3.6957 2.9464) (xy -3.6957 -2.144522) (xy -4.2418 -2.144522)
				(xy -4.2418 -2.855722) (xy -3.6957 -2.855722) (xy -3.6957 -3.9878) (xy -3.302 -3.9878) (xy -3.302 -1.7907)
				(xy 3.302 -1.7907) (xy 3.302 -3.9878) (xy 3.6957 -3.9878) (xy 3.6957 -2.855722) (xy 4.2418 -2.855722)
				(xy 4.2418 -2.144522) (xy 3.6957 -2.144522) (xy 3.6957 2.9464) (xy 1.7526 2.9464) (xy 1.7526 8.3566)
			)
			(stroke
				(width 0)
				(type default)
			)
			(fill no)
			(layer "F.CrtYd")
		)
		(fp_poly
			(pts
				(xy -2.2606 8.8646) (xy -2.2606 3.4544) (xy -4.2037 3.4544) (xy -4.2037 -1.2827) (xy -4.7498 -1.2827)
				(xy -4.7498 -4.4958) (xy -2.286 -4.4958) (xy -2.286 -2.3114) (xy 2.286 -2.3114) (xy 2.286 -4.4958)
				(xy 4.7498 -4.4958) (xy 4.7498 -1.2827) (xy 4.2037 -1.2827) (xy 4.2037 -0.5588) (xy 3.695954 -0.5588)
				(xy 3.695954 -2.144268) (xy 4.2418 -2.144268) (xy 4.2418 -2.855976) (xy 3.695954 -2.855976) (xy 3.695954 -3.988054)
				(xy 3.301746 -3.988054) (xy 3.301746 -1.7907) (xy -3.301746 -1.7907) (xy -3.301746 -3.988054) (xy -3.695954 -3.988054)
				(xy -3.695954 -2.855976) (xy -4.2418 -2.855976) (xy -4.2418 -2.144268) (xy -3.695954 -2.144268)
				(xy -3.695954 2.9464) (xy -1.752854 2.9464) (xy -1.752854 8.3566) (xy 1.752854 8.3566) (xy 1.752854 2.9464)
				(xy 3.695954 2.9464) (xy 3.695954 -0.5461) (xy 4.2037 -0.5461) (xy 4.2037 3.4544) (xy 2.2606 3.4544)
				(xy 2.2606 8.8646)
			)
			(stroke
				(width 0)
				(type default)
			)
			(fill no)
			(layer "F.CrtYd")
		)
		(fp_poly
			(pts
				(xy 2.2606 8.8646) (xy -2.2606 8.8646) (xy -2.2606 3.4544) (xy -4.2037 3.4544) (xy -4.2037 -1.2827)
				(xy -4.7498 -1.2827) (xy -4.7498 -4.4958) (xy -2.286 -4.4958) (xy -2.286 -2.3114) (xy 2.286 -2.3114)
				(xy 2.286 -4.4958) (xy 4.7498 -4.4958) (xy 4.7498 -1.2827) (xy 4.2037 -1.2827) (xy 4.2037 3.4544)
				(xy 2.2606 3.4544)
			)
			(stroke
				(width 0)
				(type default)
			)
			(fill no)
			(layer "F.Fab")
		)
		(pad "1" thru_hole circle
			(at -2.249932 0)
			(size 1.4224 1.4224)
			(drill 1.016)
			(layers "*.Cu" "*.Mask")
			(remove_unused_layers no)
			(net "FP_PWR_BTN_N")
			(clearance 0.1524)
			(thermal_gap 0.1524)
		)
		(pad "2" thru_hole circle
			(at 2.249932 0)
			(size 1.4224 1.4224)
			(drill 1.016)
			(layers "*.Cu" "*.Mask")
			(remove_unused_layers no)
			(net "GND")
			(clearance 0.1524)
			(thermal_gap 0.1524)
		)
		(pad "3" thru_hole circle
			(at -3.50012 -2.500122)
			(size 1.4224 1.4224)
			(drill 1.016)
			(layers "*.Cu" "*.Mask")
			(remove_unused_layers no)
			(net "PWR_BTN_GND")
			(clearance 0.1524)
			(thermal_gap 0.1524)
		)
		(pad "4" thru_hole circle
			(at 3.50012 -2.500122)
			(size 1.4224 1.4224)
			(drill 1.016)
			(layers "*.Cu" "*.Mask")
			(remove_unused_layers no)
			(net "PWR_BTN_GND")
			(clearance 0.1524)
			(thermal_gap 0.1524)
		)
	)
)
